(kicad_pcb
	(version 20260206)
	(generator "pcbnew")
	(generator_version "10.0")
	(general
		(thickness 1.6)
		(legacy_teardrops no)
	)
	(paper "A4")
	(title_block
		(title "04192023_DAF0TMB3IC0_F0TG_MB_C_brd_V02_OCP.brd")
		(comment 1 "Grand Teton / footprints 1537-1541 of 8354")
	)
	(layers
		(0 "F.Cu" signal "TOP")
		(4 "In1.Cu" signal "GND")
		(6 "In2.Cu" signal "IN1")
		(8 "In3.Cu" signal "GND1")
		(10 "In4.Cu" signal "IN2")
		(12 "In5.Cu" signal "GND2")
		(14 "In6.Cu" signal "IN3")
		(16 "In7.Cu" signal "GND3")
		(18 "In8.Cu" signal "VCC")
		(20 "In9.Cu" signal "VCC1")
		(22 "In10.Cu" signal "GND4")
		(24 "In11.Cu" signal "IN4")
		(26 "In12.Cu" signal "GND5")
		(28 "In13.Cu" signal "IN5")
		(30 "In14.Cu" signal "GND6")
		(32 "In15.Cu" signal "IN6")
		(34 "In16.Cu" signal "GND7")
		(2 "B.Cu" signal "BOTTOM")
		(9 "F.Adhes" user "F.Adhesive")
		(11 "B.Adhes" user "B.Adhesive")
		(13 "F.Paste" user "Package Geometry/Pastemask Top")
		(15 "B.Paste" user "Package Geometry/Pastemask Bottom")
		(5 "F.SilkS" user "Ref Des/Silkscreen Top")
		(7 "B.SilkS" user "Ref Des/Silkscreen Bottom")
		(1 "F.Mask" user "Board Geometry/Soldermask Top")
		(3 "B.Mask" user "Board Geometry/Soldermask Bottom")
		(17 "Dwgs.User" user "User.Drawings")
		(19 "Cmts.User" user "User.Comments")
		(21 "Eco1.User" user "User.Eco1")
		(23 "Eco2.User" user "User.Eco2")
		(25 "Edge.Cuts" user "Board Geometry/Outline")
		(27 "Margin" user)
		(31 "F.CrtYd" user "Package Geometry/Place Bound Top")
		(29 "B.CrtYd" user "Package Geometry/Place Bound Bottom")
		(35 "F.Fab" user "Ref Des/Assembly Top")
		(33 "B.Fab" user "Ref Des/Assembly Bottom")
	)
	(footprint ""
		(layer "F.Cu")
		(at 429.024542 -428.30623 90)
		(property "Reference" "U6005"
			(at -0.025908 5.518658 90)
			(unlocked yes)
			(layer "F.SilkS")
			(effects
				(font
					(size 0.7874 0.5842)
					(thickness 0.1524)
				)
			)
		)
		(property "Value" ""
			(at 0 0 90)
			(layer "F.Fab")
			(effects
				(font
					(size 1.27 1.27)
				)
			)
		)
		(duplicate_pad_numbers_are_jumpers no)
		(fp_line
			(start 1.500124 -1.500124)
			(end 1.500124 -1.004062)
			(stroke
				(width 0.1524)
				(type default)
			)
			(layer "F.SilkS")
		)
		(fp_line
			(start 1.004062 -1.500124)
			(end 1.500124 -1.500124)
			(stroke
				(width 0.1524)
				(type default)
			)
			(layer "F.SilkS")
		)
		(fp_line
			(start -1.500124 -1.500124)
			(end -1.004062 -1.500124)
			(stroke
				(width 0.1524)
				(type default)
			)
			(layer "F.SilkS")
		)
		(fp_line
			(start -1.500124 -1.004062)
			(end -1.500124 -1.500124)
			(stroke
				(width 0.1524)
				(type default)
			)
			(layer "F.SilkS")
		)
		(fp_line
			(start 1.500124 1.004062)
			(end 1.500124 1.500124)
			(stroke
				(width 0.1524)
				(type default)
			)
			(layer "F.SilkS")
		)
		(fp_line
			(start 1.500124 1.500124)
			(end 1.004062 1.500124)
			(stroke
				(width 0.1524)
				(type default)
			)
			(layer "F.SilkS")
		)
		(fp_line
			(start -1.004062 1.500124)
			(end -1.500124 1.500124)
			(stroke
				(width 0.1524)
				(type default)
			)
			(layer "F.SilkS")
		)
		(fp_line
			(start -1.500124 1.500124)
			(end -1.500124 1.004062)
			(stroke
				(width 0.1524)
				(type default)
			)
			(layer "F.SilkS")
		)
		(fp_poly
			(pts
				(xy -1.862328 -1.148588) (xy -2.88036 -1.652778) (xy -2.069592 -2.265426)
			)
			(stroke
				(width 0)
				(type default)
			)
			(fill yes)
			(layer "F.SilkS")
		)
		(fp_line
			(start 1.500124 -1.500124)
			(end 1.500124 1.500124)
			(stroke
				(width 0.1)
				(type default)
			)
			(layer "F.Fab")
		)
		(fp_line
			(start -1.500124 -1.500124)
			(end 1.500124 -1.500124)
			(stroke
				(width 0.1)
				(type default)
			)
			(layer "F.Fab")
		)
		(fp_line
			(start 1.500124 1.500124)
			(end -1.500124 1.500124)
			(stroke
				(width 0.1)
				(type default)
			)
			(layer "F.Fab")
		)
		(fp_line
			(start -1.500124 1.500124)
			(end -1.500124 -1.500124)
			(stroke
				(width 0.1)
				(type default)
			)
			(layer "F.Fab")
		)
		(fp_poly
			(pts
				(xy -2.847848 -1.258062) (xy -2.847848 -0.242062) (xy -1.831848 -0.750062)
			)
			(stroke
				(width 0)
				(type default)
			)
			(fill yes)
			(layer "F.Fab")
		)
		(pad "1" smd rect
			(at -1.400048 -0.750062)
			(size 0.2286 0.6096)
			(layers "F.Cu" "F.Mask" "F.Paste")
			(net "HSC_TYPE_ADC_A1")
		)
		(pad "2" smd rect
			(at -1.400048 -0.249936)
			(size 0.2286 0.6096)
			(layers "F.Cu" "F.Mask" "F.Paste")
			(net "HSC_TYPE_ADC_A0")
		)
		(pad "3" smd rect
			(at -1.400048 0.249936)
			(size 0.2286 0.6096)
			(layers "F.Cu" "F.Mask" "F.Paste")
			(net "HSC_TYPE_ADC_ALERT")
		)
		(pad "4" smd rect
			(at -1.400048 0.750062)
			(size 0.2286 0.6096)
			(layers "F.Cu" "F.Mask" "F.Paste")
			(net "SMB_HSC_TYPE_ADC_SDA")
		)
		(pad "5" smd rect
			(at -0.750062 1.400048 90)
			(size 0.2286 0.6096)
			(layers "F.Cu" "F.Mask" "F.Paste")
			(net "SMB_HSC_TYPE_ADC_SCL")
		)
		(pad "6" smd rect
			(at -0.249936 1.400048 90)
			(size 0.2286 0.6096)
			(layers "F.Cu" "F.Mask" "F.Paste")
			(net "NC_HSC_TYPE_NC0")
		)
		(pad "7" smd rect
			(at 0.249936 1.400048 90)
			(size 0.2286 0.6096)
			(layers "F.Cu" "F.Mask" "F.Paste")
			(net "NC_HSC_TYPE_NC1")
		)
		(pad "8" smd rect
			(at 0.750062 1.400048 90)
			(size 0.2286 0.6096)
			(layers "F.Cu" "F.Mask" "F.Paste")
			(net "NC_HSC_TYPE_NC2")
		)
		(pad "9" smd rect
			(at 1.400048 0.750062)
			(size 0.2286 0.6096)
			(layers "F.Cu" "F.Mask" "F.Paste")
			(net "P3V3_AUX")
		)
		(pad "10" smd rect
			(at 1.400048 0.249936)
			(size 0.2286 0.6096)
			(layers "F.Cu" "F.Mask" "F.Paste")
			(net "GND")
		)
		(pad "11" smd rect
			(at 1.400048 -0.249936)
			(size 0.2286 0.6096)
			(layers "F.Cu" "F.Mask" "F.Paste")
			(net "HSC_TYPE_ADC")
		)
		(pad "12" smd rect
			(at 1.400048 -0.750062)
			(size 0.2286 0.6096)
			(layers "F.Cu" "F.Mask" "F.Paste")
			(net "NC_HSC_TYPE_VINM")
		)
		(pad "13" smd rect
			(at 0.750062 -1.400048 90)
			(size 0.2286 0.6096)
			(layers "F.Cu" "F.Mask" "F.Paste")
			(net "NC_HSC_TYPE_VINP")
		)
		(pad "14" smd rect
			(at 0.249936 -1.400048 90)
			(size 0.2286 0.6096)
			(layers "F.Cu" "F.Mask" "F.Paste")
			(net "NC_HSC_TYPE_NC3")
		)
		(pad "15" smd rect
			(at -0.249936 -1.400048 90)
			(size 0.2286 0.6096)
			(layers "F.Cu" "F.Mask" "F.Paste")
			(net "NC_HSC_TYPE_NC4")
		)
		(pad "16" smd rect
			(at -0.750062 -1.400048 90)
			(size 0.2286 0.6096)
			(layers "F.Cu" "F.Mask" "F.Paste")
			(net "NC_HSC_TYPE_NC5")
		)
		(pad "TH" smd rect
			(at 0 0 90)
			(size 1.7018 1.7018)
			(layers "F.Cu" "F.Mask" "F.Paste")
			(net "GND")
		)
		(zone
			(layer "F.Cu")
			(hatch none 0.5)
			(connect_pads
				(clearance 0)
			)
			(min_thickness 0.25)
			(keepout
				(tracks not_allowed)
				(vias allowed)
				(pads allowed)
				(copperpour not_allowed)
				(footprints allowed)
			)
			(placement
				(enabled no)
				(sheetname "")
			)
			(fill
				(thermal_gap 0.5)
				(thermal_bridge_width 0.5)
				(island_removal_mode 0)
			)
			(polygon
				(pts
					(xy 429.024542 -427.261782) (xy 429.024542 -427.40453) (xy 429.926242 -427.40453) (xy 429.926242 -429.20793)
					(xy 429.538638 -429.20793) (xy 429.538638 -429.350678) (xy 430.06899 -429.350678) (xy 430.06899 -427.261782)
				)
			)
		)
	)
	(footprint ""
		(layer "F.Cu")
		(at 193.809366 -37.43325 90)
		(property "Reference" "Q39"
			(at -2.361946 -0.526796 0)
			(unlocked yes)
			(layer "F.SilkS")
			(effects
				(font
					(size 0.7874 0.5842)
					(thickness 0.1524)
				)
				(justify left)
			)
		)
		(property "Value" ""
			(at 0 0 90)
			(layer "F.Fab")
			(effects
				(font
					(size 1.27 1.27)
				)
			)
		)
		(duplicate_pad_numbers_are_jumpers no)
		(fp_line
			(start 1.603248 -1.500124)
			(end 1.603248 1.500124)
			(stroke
				(width 0.1524)
				(type default)
			)
			(layer "F.SilkS")
		)
		(fp_line
			(start -1.603248 -1.500124)
			(end 1.603248 -1.500124)
			(stroke
				(width 0.1524)
				(type default)
			)
			(layer "F.SilkS")
		)
		(fp_line
			(start 1.603248 1.500124)
			(end -1.603248 1.500124)
			(stroke
				(width 0.1524)
				(type default)
			)
			(layer "F.SilkS")
		)
		(fp_line
			(start -1.603248 1.500124)
			(end -1.603248 -1.500124)
			(stroke
				(width 0.1524)
				(type default)
			)
			(layer "F.SilkS")
		)
		(fp_line
			(start 0.700024 -1.500124)
			(end -0.700024 -1.500124)
			(stroke
				(width 0.1)
				(type default)
			)
			(layer "F.Fab")
		)
		(fp_line
			(start -0.700024 -1.500124)
			(end -0.700024 -1.169924)
			(stroke
				(width 0.1)
				(type default)
			)
			(layer "F.Fab")
		)
		(fp_line
			(start -0.700024 -1.169924)
			(end -1.249934 -1.169924)
			(stroke
				(width 0.1)
				(type default)
			)
			(layer "F.Fab")
		)
		(fp_line
			(start -1.249934 -1.169924)
			(end -1.249934 -0.729996)
			(stroke
				(width 0.1)
				(type default)
			)
			(layer "F.Fab")
		)
		(fp_line
			(start -0.6985 -0.729996)
			(end -0.6985 0.729996)
			(stroke
				(width 0.1)
				(type default)
			)
			(layer "F.Fab")
		)
		(fp_line
			(start -1.249934 -0.729996)
			(end -0.6985 -0.729996)
			(stroke
				(width 0.1)
				(type default)
			)
			(layer "F.Fab")
		)
		(fp_line
			(start 1.249934 -0.219964)
			(end 0.700024 -0.219964)
			(stroke
				(width 0.1)
				(type default)
			)
			(layer "F.Fab")
		)
		(fp_line
			(start 0.700024 -0.219964)
			(end 0.700024 -1.500124)
			(stroke
				(width 0.1)
				(type default)
			)
			(layer "F.Fab")
		)
		(fp_line
			(start 1.249934 0.219964)
			(end 1.249934 -0.219964)
			(stroke
				(width 0.1)
				(type default)
			)
			(layer "F.Fab")
		)
		(fp_line
			(start 0.700024 0.219964)
			(end 1.249934 0.219964)
			(stroke
				(width 0.1)
				(type default)
			)
			(layer "F.Fab")
		)
		(fp_line
			(start -0.6985 0.729996)
			(end -1.249934 0.729996)
			(stroke
				(width 0.1)
				(type default)
			)
			(layer "F.Fab")
		)
		(fp_line
			(start -1.249934 0.729996)
			(end -1.249934 1.169924)
			(stroke
				(width 0.1)
				(type default)
			)
			(layer "F.Fab")
		)
		(fp_line
			(start -0.700024 1.169924)
			(end -0.700024 1.500124)
			(stroke
				(width 0.1)
				(type default)
			)
			(layer "F.Fab")
		)
		(fp_line
			(start -1.249934 1.169924)
			(end -0.700024 1.169924)
			(stroke
				(width 0.1)
				(type default)
			)
			(layer "F.Fab")
		)
		(fp_line
			(start 0.700024 1.500124)
			(end 0.700024 0.219964)
			(stroke
				(width 0.1)
				(type default)
			)
			(layer "F.Fab")
		)
		(fp_line
			(start -0.700024 1.500124)
			(end 0.700024 1.500124)
			(stroke
				(width 0.1)
				(type default)
			)
			(layer "F.Fab")
		)
		(fp_rect
			(start -0.700024 1.500124)
			(end 0.700024 -1.500124)
			(stroke
				(width 0)
				(type default)
			)
			(fill no)
			(layer "F.Fab")
		)
		(pad "D" smd rect
			(at 0.999998 0)
			(size 0.8128 0.9144)
			(layers "F.Cu" "F.Mask" "F.Paste")
			(net "P12V_SCM_EN")
		)
		(pad "G" smd rect
			(at -0.999998 -0.94996)
			(size 0.8128 0.9144)
			(layers "F.Cu" "F.Mask" "F.Paste")
			(net "FM_SCM_PRSNT1_R_N")
		)
		(pad "S" smd rect
			(at -0.999998 0.94996)
			(size 0.8128 0.9144)
			(layers "F.Cu" "F.Mask" "F.Paste")
			(net "GND")
		)
	)
	(footprint ""
		(layer "F.Cu")
		(at 463.18932 -38.565836 180)
		(property "Reference" "R2488"
			(at 0 0 180)
			(layer "F.SilkS")
			(hide yes)
			(effects
				(font
					(size 1.27 1.27)
				)
			)
		)
		(property "Value" ""
			(at 0 0 180)
			(layer "F.Fab")
			(effects
				(font
					(size 1.27 1.27)
				)
			)
		)
		(duplicate_pad_numbers_are_jumpers no)
		(fp_line
			(start 0.7874 0.4064)
			(end -0.7874 0.4064)
			(stroke
				(width 0.1524)
				(type default)
			)
			(layer "F.SilkS")
		)
		(fp_line
			(start 0.7874 -0.4064)
			(end 0.7874 0.4064)
			(stroke
				(width 0.1524)
				(type default)
			)
			(layer "F.SilkS")
		)
		(fp_line
			(start -0.7874 0.4064)
			(end -0.7874 -0.4064)
			(stroke
				(width 0.1524)
				(type default)
			)
			(layer "F.SilkS")
		)
		(fp_line
			(start -0.7874 -0.4064)
			(end 0.7874 -0.4064)
			(stroke
				(width 0.1524)
				(type default)
			)
			(layer "F.SilkS")
		)
		(fp_line
			(start 0.67945 0.3048)
			(end 0.120396 0.3048)
			(stroke
				(width 0.1)
				(type default)
			)
			(layer "F.Fab")
		)
		(fp_line
			(start 0.67945 -0.3048)
			(end 0.67945 0.3048)
			(stroke
				(width 0.1)
				(type default)
			)
			(layer "F.Fab")
		)
		(fp_line
			(start 0.12065 -0.2794)
			(end 0.12065 -0.3048)
			(stroke
				(width 0.1)
				(type default)
			)
			(layer "F.Fab")
		)
		(fp_line
			(start 0.12065 -0.3048)
			(end 0.67945 -0.3048)
			(stroke
				(width 0.1)
				(type default)
			)
			(layer "F.Fab")
		)
		(fp_line
			(start 0.120396 0.3048)
			(end 0.120396 0.2794)
			(stroke
				(width 0.1)
				(type default)
			)
			(layer "F.Fab")
		)
		(fp_line
			(start 0.120396 0.2794)
			(end -0.12065 0.2794)
			(stroke
				(width 0.1)
				(type default)
			)
			(layer "F.Fab")
		)
		(fp_line
			(start -0.12065 0.3048)
			(end -0.67945 0.3048)
			(stroke
				(width 0.1)
				(type default)
			)
			(layer "F.Fab")
		)
		(fp_line
			(start -0.12065 0.2794)
			(end -0.12065 0.3048)
			(stroke
				(width 0.1)
				(type default)
			)
			(layer "F.Fab")
		)
		(fp_line
			(start -0.12065 -0.2794)
			(end 0.12065 -0.2794)
			(stroke
				(width 0.1)
				(type default)
			)
			(layer "F.Fab")
		)
		(fp_line
			(start -0.12065 -0.305054)
			(end -0.12065 -0.2794)
			(stroke
				(width 0.1)
				(type default)
			)
			(layer "F.Fab")
		)
		(fp_line
			(start -0.67945 0.3048)
			(end -0.67945 -0.305054)
			(stroke
				(width 0.1)
				(type default)
			)
			(layer "F.Fab")
		)
		(fp_line
			(start -0.67945 -0.305054)
			(end -0.12065 -0.305054)
			(stroke
				(width 0.1)
				(type default)
			)
			(layer "F.Fab")
		)
		(pad "1" smd circle
			(at -0.40005 0 180)
			(size 0 0)
			(layers "F.Cu" "F.Mask" "F.Paste")
			(net "P3V3_AUX")
		)
		(pad "2" smd circle
			(at 0.40005 0 180)
			(size 0 0)
			(layers "F.Cu" "F.Mask" "F.Paste")
			(net "OCP_SFF_WAKE_BUFF_N")
		)
	)
	(footprint ""
		(layer "F.Cu")
		(at 205.232 -128.016)
		(property "Reference" "R6050"
			(at 0 0 0)
			(layer "F.SilkS")
			(hide yes)
			(effects
				(font
					(size 1.27 1.27)
				)
			)
		)
		(property "Value" ""
			(at 0 0 0)
			(layer "F.Fab")
			(effects
				(font
					(size 1.27 1.27)
				)
			)
		)
		(duplicate_pad_numbers_are_jumpers no)
		(fp_line
			(start -0.7874 -0.4064)
			(end 0.7874 -0.4064)
			(stroke
				(width 0.1524)
				(type default)
			)
			(layer "F.SilkS")
		)
		(fp_line
			(start -0.7874 0.4064)
			(end -0.7874 -0.4064)
			(stroke
				(width 0.1524)
				(type default)
			)
			(layer "F.SilkS")
		)
		(fp_line
			(start 0.7874 -0.4064)
			(end 0.7874 0.4064)
			(stroke
				(width 0.1524)
				(type default)
			)
			(layer "F.SilkS")
		)
		(fp_line
			(start 0.7874 0.4064)
			(end -0.7874 0.4064)
			(stroke
				(width 0.1524)
				(type default)
			)
			(layer "F.SilkS")
		)
		(fp_line
			(start -0.67945 -0.305054)
			(end -0.12065 -0.305054)
			(stroke
				(width 0.1)
				(type default)
			)
			(layer "F.Fab")
		)
		(fp_line
			(start -0.67945 0.3048)
			(end -0.67945 -0.305054)
			(stroke
				(width 0.1)
				(type default)
			)
			(layer "F.Fab")
		)
		(fp_line
			(start -0.12065 -0.305054)
			(end -0.12065 -0.2794)
			(stroke
				(width 0.1)
				(type default)
			)
			(layer "F.Fab")
		)
		(fp_line
			(start -0.12065 -0.2794)
			(end 0.12065 -0.2794)
			(stroke
				(width 0.1)
				(type default)
			)
			(layer "F.Fab")
		)
		(fp_line
			(start -0.12065 0.2794)
			(end -0.12065 0.3048)
			(stroke
				(width 0.1)
				(type default)
			)
			(layer "F.Fab")
		)
		(fp_line
			(start -0.12065 0.3048)
			(end -0.67945 0.3048)
			(stroke
				(width 0.1)
				(type default)
			)
			(layer "F.Fab")
		)
		(fp_line
			(start 0.120396 0.2794)
			(end -0.12065 0.2794)
			(stroke
				(width 0.1)
				(type default)
			)
			(layer "F.Fab")
		)
		(fp_line
			(start 0.120396 0.3048)
			(end 0.120396 0.2794)
			(stroke
				(width 0.1)
				(type default)
			)
			(layer "F.Fab")
		)
		(fp_line
			(start 0.12065 -0.3048)
			(end 0.67945 -0.3048)
			(stroke
				(width 0.1)
				(type default)
			)
			(layer "F.Fab")
		)
		(fp_line
			(start 0.12065 -0.2794)
			(end 0.12065 -0.3048)
			(stroke
				(width 0.1)
				(type default)
			)
			(layer "F.Fab")
		)
		(fp_line
			(start 0.67945 -0.3048)
			(end 0.67945 0.3048)
			(stroke
				(width 0.1)
				(type default)
			)
			(layer "F.Fab")
		)
		(fp_line
			(start 0.67945 0.3048)
			(end 0.120396 0.3048)
			(stroke
				(width 0.1)
				(type default)
			)
			(layer "F.Fab")
		)
		(pad "1" smd circle
			(at -0.40005 0)
			(size 0 0)
			(layers "F.Cu" "F.Mask" "F.Paste")
			(net "SW_P3V3_EN")
		)
		(pad "2" smd circle
			(at 0.40005 0)
			(size 0 0)
			(layers "F.Cu" "F.Mask" "F.Paste")
			(net "GND")
		)
	)
	(footprint ""
		(layer "F.Cu")
		(at 402.253958 -328.418952 180)
		(property "Reference" "R467"
			(at 0 0 180)
			(layer "F.SilkS")
			(hide yes)
			(effects
				(font
					(size 1.27 1.27)
				)
			)
		)
		(property "Value" ""
			(at 0 0 180)
			(layer "F.Fab")
			(effects
				(font
					(size 1.27 1.27)
				)
			)
		)
		(duplicate_pad_numbers_are_jumpers no)
		(fp_line
			(start 0.7874 0.4064)
			(end -0.7874 0.4064)
			(stroke
				(width 0.1524)
				(type default)
			)
			(layer "F.SilkS")
		)
		(fp_line
			(start 0.7874 -0.4064)
			(end 0.7874 0.4064)
			(stroke
				(width 0.1524)
				(type default)
			)
			(layer "F.SilkS")
		)
		(fp_line
			(start -0.7874 0.4064)
			(end -0.7874 -0.4064)
			(stroke
				(width 0.1524)
				(type default)
			)
			(layer "F.SilkS")
		)
		(fp_line
			(start -0.7874 -0.4064)
			(end 0.7874 -0.4064)
			(stroke
				(width 0.1524)
				(type default)
			)
			(layer "F.SilkS")
		)
		(fp_line
			(start 0.67945 0.3048)
			(end 0.120396 0.3048)
			(stroke
				(width 0.1)
				(type default)
			)
			(layer "F.Fab")
		)
		(fp_line
			(start 0.67945 -0.3048)
			(end 0.67945 0.3048)
			(stroke
				(width 0.1)
				(type default)
			)
			(layer "F.Fab")
		)
		(fp_line
			(start 0.12065 -0.2794)
			(end 0.12065 -0.3048)
			(stroke
				(width 0.1)
				(type default)
			)
			(layer "F.Fab")
		)
		(fp_line
			(start 0.12065 -0.3048)
			(end 0.67945 -0.3048)
			(stroke
				(width 0.1)
				(type default)
			)
			(layer "F.Fab")
		)
		(fp_line
			(start 0.120396 0.3048)
			(end 0.120396 0.2794)
			(stroke
				(width 0.1)
				(type default)
			)
			(layer "F.Fab")
		)
		(fp_line
			(start 0.120396 0.2794)
			(end -0.12065 0.2794)
			(stroke
				(width 0.1)
				(type default)
			)
			(layer "F.Fab")
		)
		(fp_line
			(start -0.12065 0.3048)
			(end -0.67945 0.3048)
			(stroke
				(width 0.1)
				(type default)
			)
			(layer "F.Fab")
		)
		(fp_line
			(start -0.12065 0.2794)
			(end -0.12065 0.3048)
			(stroke
				(width 0.1)
				(type default)
			)
			(layer "F.Fab")
		)
		(fp_line
			(start -0.12065 -0.2794)
			(end 0.12065 -0.2794)
			(stroke
				(width 0.1)
				(type default)
			)
			(layer "F.Fab")
		)
		(fp_line
			(start -0.12065 -0.305054)
			(end -0.12065 -0.2794)
			(stroke
				(width 0.1)
				(type default)
			)
			(layer "F.Fab")
		)
		(fp_line
			(start -0.67945 0.3048)
			(end -0.67945 -0.305054)
			(stroke
				(width 0.1)
				(type default)
			)
			(layer "F.Fab")
		)
		(fp_line
			(start -0.67945 -0.305054)
			(end -0.12065 -0.305054)
			(stroke
				(width 0.1)
				(type default)
			)
			(layer "F.Fab")
		)
		(pad "1" smd circle
			(at -0.40005 0 180)
			(size 0 0)
			(layers "F.Cu" "F.Mask" "F.Paste")
			(net "SPI_CPU0_D3")
		)
		(pad "2" smd circle
			(at 0.40005 0 180)
			(size 0 0)
			(layers "F.Cu" "F.Mask" "F.Paste")
			(net "SPI_CPU0_R_D3")
		)
	)
)
